(kicad_pcb
	(version 20260206)
	(generator "pcbnew")
	(generator_version "10.0")
	(general
		(thickness 1.6)
		(legacy_teardrops no)
	)
	(paper "A4")
	(title_block
		(title "Bryce Canyon_R.DPB_16317-1_OCP.brd")
		(comment 1 "Bryce Canyon / footprints 375-382 of 2099")
	)
	(layers
		(0 "F.Cu" signal "TOP")
		(4 "In1.Cu" signal "L2GND")
		(6 "In2.Cu" signal "L3")
		(8 "In3.Cu" signal "L4VCC")
		(10 "In4.Cu" signal "L5VCC")
		(12 "In5.Cu" signal "L6")
		(14 "In6.Cu" signal "L7GND")
		(2 "B.Cu" signal "BOTTOM")
		(9 "F.Adhes" user "F.Adhesive")
		(11 "B.Adhes" user "B.Adhesive")
		(13 "F.Paste" user "Package Geometry/Pastemask Top")
		(15 "B.Paste" user "Package Geometry/Pastemask Bottom")
		(5 "F.SilkS" user "Ref Des/Silkscreen Top")
		(7 "B.SilkS" user "Ref Des/Silkscreen Bottom")
		(1 "F.Mask" user "Board Geometry/Soldermask Top")
		(3 "B.Mask" user "Board Geometry/Soldermask Bottom")
		(17 "Dwgs.User" user "User.Drawings")
		(19 "Cmts.User" user "User.Comments")
		(21 "Eco1.User" user "User.Eco1")
		(23 "Eco2.User" user "User.Eco2")
		(25 "Edge.Cuts" user "Board Geometry/Outline")
		(27 "Margin" user)
		(31 "F.CrtYd" user "Package Geometry/Place Bound Top")
		(29 "B.CrtYd" user "Package Geometry/Place Bound Bottom")
		(35 "F.Fab" user "Ref Des/Assembly Top")
		(33 "B.Fab" user "Ref Des/Assembly Bottom")
	)
	(footprint ""
		(layer "F.Cu")
		(at 85.5218 -16.1798 -90)
		(property "Reference" "R679"
			(at 0 0 270)
			(layer "F.SilkS")
			(hide yes)
			(effects
				(font
					(size 1.27 1.27)
				)
			)
		)
		(property "Value" "0R2J-2-GP"
			(at 0.064008 -3.993896 270)
			(unlocked yes)
			(layer "F.Fab")
			(hide yes)
			(effects
				(font
					(size 1.016 1.016)
					(thickness 0.1524)
				)
			)
		)
		(property "Device Type" "R402H16"
			(at 0.064008 -5.517896 270)
			(unlocked yes)
			(layer "F.Fab")
			(hide yes)
			(effects
				(font
					(size 1.016 1.016)
					(thickness 0.1524)
				)
			)
		)
		(duplicate_pad_numbers_are_jumpers no)
		(fp_line
			(start -0.508 -0.9398)
			(end -0.508 0.9398)
			(stroke
				(width 0.1524)
				(type default)
			)
			(layer "F.SilkS")
		)
		(fp_line
			(start 0.508 -0.9398)
			(end -0.508 -0.9398)
			(stroke
				(width 0.1524)
				(type default)
			)
			(layer "F.SilkS")
		)
		(fp_rect
			(start -0.508 0.9398)
			(end 0.508 -0.9398)
			(stroke
				(width 0)
				(type default)
			)
			(fill no)
			(layer "F.CrtYd")
		)
		(fp_rect
			(start -0.508 0.9398)
			(end 0.508 -0.9398)
			(stroke
				(width 0)
				(type default)
			)
			(fill no)
			(layer "F.Fab")
		)
		(pad "1" smd custom
			(at 0 -0.4445 270)
			(size 0.1397 0.1397)
			(layers "F.Cu" "F.Mask" "F.Paste")
			(net "DRIVE_B_26_PWR")
			(options
				(clearance outline)
				(anchor circle)
			)
			(primitives
				(gr_poly
					(pts
						(arc
							(start -0.1778 -0.2794)
							(mid -0.249642 -0.249642)
							(end -0.2794 -0.1778)
						)
						(arc
							(start -0.2794 0.1778)
							(mid -0.249642 0.249642)
							(end -0.1778 0.2794)
						)
						(arc
							(start 0.1778 0.2794)
							(mid 0.249642 0.249642)
							(end 0.2794 0.1778)
						)
						(arc
							(start 0.2794 -0.1778)
							(mid 0.249642 -0.249642)
							(end 0.1778 -0.2794)
						)
					)
					(width 0)
					(fill yes)
				)
			)
		)
		(pad "2" smd custom
			(at 0 0.4445 270)
			(size 0.1397 0.1397)
			(layers "F.Cu" "F.Mask" "F.Paste")
			(net "SW_PWR_R_HDD26")
			(options
				(clearance outline)
				(anchor circle)
			)
			(primitives
				(gr_poly
					(pts
						(arc
							(start -0.1778 -0.2794)
							(mid -0.249642 -0.249642)
							(end -0.2794 -0.1778)
						)
						(arc
							(start -0.2794 0.1778)
							(mid -0.249642 0.249642)
							(end -0.1778 0.2794)
						)
						(arc
							(start 0.1778 0.2794)
							(mid 0.249642 0.249642)
							(end 0.2794 0.1778)
						)
						(arc
							(start 0.2794 -0.1778)
							(mid 0.249642 -0.249642)
							(end 0.1778 -0.2794)
						)
					)
					(width 0)
					(fill yes)
				)
			)
		)
	)
	(footprint ""
		(layer "F.Cu")
		(at 285.90621 -333.51978 180)
		(property "Reference" "C19"
			(at 0 0 180)
			(layer "F.SilkS")
			(hide yes)
			(effects
				(font
					(size 1.27 1.27)
				)
			)
		)
		(property "Value" "SCD1U16V2KX-3GP"
			(at 1.1811 -2.7051 180)
			(unlocked yes)
			(layer "F.Fab")
			(hide yes)
			(effects
				(font
					(size 1.016 1.016)
					(thickness 0.1524)
				)
			)
		)
		(property "Device Type" "C402H22"
			(at 1.1811 -4.2291 180)
			(unlocked yes)
			(layer "F.Fab")
			(hide yes)
			(effects
				(font
					(size 1.016 1.016)
					(thickness 0.1524)
				)
			)
		)
		(duplicate_pad_numbers_are_jumpers no)
		(fp_rect
			(start -0.4318 0.9525)
			(end 0.4318 -0.9525)
			(stroke
				(width 0)
				(type default)
			)
			(fill no)
			(layer "F.CrtYd")
		)
		(fp_rect
			(start -0.4318 0.9525)
			(end 0.4318 -0.9525)
			(stroke
				(width 0)
				(type default)
			)
			(fill no)
			(layer "F.Fab")
		)
		(pad "1" smd custom
			(at 0 -0.4445 180)
			(size 0.1524 0.1524)
			(layers "F.Cu" "F.Mask" "F.Paste")
			(net "P3V3_IN")
			(options
				(clearance outline)
				(anchor circle)
			)
			(primitives
				(gr_poly
					(pts
						(arc
							(start 0.3048 -0.2032)
							(mid 0.275042 -0.275042)
							(end 0.2032 -0.3048)
						)
						(arc
							(start -0.2032 -0.3048)
							(mid -0.275042 -0.275042)
							(end -0.3048 -0.2032)
						)
						(arc
							(start -0.3048 0.2032)
							(mid -0.275042 0.275042)
							(end -0.2032 0.3048)
						)
						(arc
							(start 0.2032 0.3048)
							(mid 0.275042 0.275042)
							(end 0.3048 0.2032)
						)
					)
					(width 0)
					(fill yes)
				)
			)
		)
		(pad "2" smd custom
			(at 0 0.4445 180)
			(size 0.1524 0.1524)
			(layers "F.Cu" "F.Mask" "F.Paste")
			(net "GND")
			(options
				(clearance outline)
				(anchor circle)
			)
			(primitives
				(gr_poly
					(pts
						(arc
							(start 0.3048 -0.2032)
							(mid 0.275042 -0.275042)
							(end 0.2032 -0.3048)
						)
						(arc
							(start -0.2032 -0.3048)
							(mid -0.275042 -0.275042)
							(end -0.3048 -0.2032)
						)
						(arc
							(start -0.3048 0.2032)
							(mid -0.275042 0.275042)
							(end -0.2032 0.3048)
						)
						(arc
							(start 0.2032 0.3048)
							(mid 0.275042 0.275042)
							(end 0.3048 0.2032)
						)
					)
					(width 0)
					(fill yes)
				)
			)
		)
	)
	(footprint ""
		(layer "F.Cu")
		(at 461.899 -128.651 180)
		(property "Reference" "R587"
			(at 0 0 180)
			(layer "F.SilkS")
			(hide yes)
			(effects
				(font
					(size 1.27 1.27)
				)
			)
		)
		(property "Value" "0R2J-2-GP"
			(at 0.064008 -3.993896 180)
			(unlocked yes)
			(layer "F.Fab")
			(hide yes)
			(effects
				(font
					(size 1.016 1.016)
					(thickness 0.1524)
				)
			)
		)
		(property "Device Type" "R402H16"
			(at 0.064008 -5.517896 180)
			(unlocked yes)
			(layer "F.Fab")
			(hide yes)
			(effects
				(font
					(size 1.016 1.016)
					(thickness 0.1524)
				)
			)
		)
		(duplicate_pad_numbers_are_jumpers no)
		(fp_line
			(start 0.508 -0.9398)
			(end -0.508 -0.9398)
			(stroke
				(width 0.1524)
				(type default)
			)
			(layer "F.SilkS")
		)
		(fp_line
			(start -0.508 -0.9398)
			(end -0.508 0.9398)
			(stroke
				(width 0.1524)
				(type default)
			)
			(layer "F.SilkS")
		)
		(fp_rect
			(start -0.508 0.9398)
			(end 0.508 -0.9398)
			(stroke
				(width 0)
				(type default)
			)
			(fill no)
			(layer "F.CrtYd")
		)
		(fp_rect
			(start -0.508 0.9398)
			(end 0.508 -0.9398)
			(stroke
				(width 0)
				(type default)
			)
			(fill no)
			(layer "F.Fab")
		)
		(pad "1" smd custom
			(at 0 -0.4445 180)
			(size 0.1397 0.1397)
			(layers "F.Cu" "F.Mask" "F.Paste")
			(net "DRIVE_B_22_PWR")
			(options
				(clearance outline)
				(anchor circle)
			)
			(primitives
				(gr_poly
					(pts
						(arc
							(start -0.1778 -0.2794)
							(mid -0.249642 -0.249642)
							(end -0.2794 -0.1778)
						)
						(arc
							(start -0.2794 0.1778)
							(mid -0.249642 0.249642)
							(end -0.1778 0.2794)
						)
						(arc
							(start 0.1778 0.2794)
							(mid 0.249642 0.249642)
							(end 0.2794 0.1778)
						)
						(arc
							(start 0.2794 -0.1778)
							(mid 0.249642 -0.249642)
							(end 0.1778 -0.2794)
						)
					)
					(width 0)
					(fill yes)
				)
			)
		)
		(pad "2" smd custom
			(at 0 0.4445 180)
			(size 0.1397 0.1397)
			(layers "F.Cu" "F.Mask" "F.Paste")
			(net "SW_PWR_R_HDD22")
			(options
				(clearance outline)
				(anchor circle)
			)
			(primitives
				(gr_poly
					(pts
						(arc
							(start -0.1778 -0.2794)
							(mid -0.249642 -0.249642)
							(end -0.2794 -0.1778)
						)
						(arc
							(start -0.2794 0.1778)
							(mid -0.249642 0.249642)
							(end -0.1778 0.2794)
						)
						(arc
							(start 0.1778 0.2794)
							(mid 0.249642 0.249642)
							(end 0.2794 0.1778)
						)
						(arc
							(start 0.2794 -0.1778)
							(mid 0.249642 -0.249642)
							(end 0.1778 -0.2794)
						)
					)
					(width 0)
					(fill yes)
				)
			)
		)
	)
	(footprint ""
		(layer "F.Cu")
		(at 129.413762 -269.705074)
		(property "Reference" "TP36"
			(at 0 0 0)
			(layer "F.SilkS")
			(hide yes)
			(effects
				(font
					(size 1.27 1.27)
				)
			)
		)
		(property "Value" "*"
			(at -0.0508 -1.6764 0)
			(unlocked yes)
			(layer "F.Fab")
			(hide yes)
			(effects
				(font
					(size 1.016 1.016)
					(thickness 0.1524)
				)
			)
		)
		(property "Device Type" "TPAD32"
			(at -0.0508 -3.2004 0)
			(unlocked yes)
			(layer "F.Fab")
			(hide yes)
			(effects
				(font
					(size 1.016 1.016)
					(thickness 0.1524)
				)
			)
		)
		(duplicate_pad_numbers_are_jumpers no)
		(fp_poly
			(pts
				(arc
					(start 0.4064 0)
					(mid -0.4064 0)
					(end 0.4064 0)
				)
			)
			(stroke
				(width 0)
				(type default)
			)
			(fill no)
			(layer "F.CrtYd")
		)
		(fp_poly
			(pts
				(arc
					(start 0.7112 0)
					(mid -0.7112 0)
					(end 0.7112 0)
				)
			)
			(stroke
				(width 0)
				(type default)
			)
			(fill no)
			(layer "F.Fab")
		)
		(pad "1" smd circle
			(at 0 0)
			(size 0.8128 0.8128)
			(layers "F.Cu" "F.Mask" "F.Paste")
			(net "ACT_HDD_3")
		)
	)
	(footprint ""
		(layer "F.Cu")
		(at 457.581 -44.958 180)
		(property "Reference" "C477"
			(at 0 0 180)
			(layer "F.SilkS")
			(hide yes)
			(effects
				(font
					(size 1.27 1.27)
				)
			)
		)
		(property "Value" "SC4D7U25V5KX-1-GP"
			(at -0.0762 -6.1214 180)
			(unlocked yes)
			(layer "F.Fab")
			(hide yes)
			(effects
				(font
					(size 1.016 1.016)
					(thickness 0.1524)
				)
			)
		)
		(property "Device Type" "C805H58"
			(at -0.0762 -8.1534 180)
			(unlocked yes)
			(layer "F.Fab")
			(hide yes)
			(effects
				(font
					(size 1.016 1.016)
					(thickness 0.1524)
				)
			)
		)
		(duplicate_pad_numbers_are_jumpers no)
		(fp_line
			(start 0.635 0)
			(end -0.635 0)
			(stroke
				(width 0.508)
				(type default)
			)
			(layer "F.SilkS")
		)
		(fp_rect
			(start -0.9652 1.778)
			(end 0.9652 -1.778)
			(stroke
				(width 0)
				(type default)
			)
			(fill no)
			(layer "F.CrtYd")
		)
		(fp_poly
			(pts
				(xy -0.9652 -1.778) (xy 0.9652 -1.778) (xy 0.9652 1.778) (xy -0.9652 1.778)
			)
			(stroke
				(width 0)
				(type default)
			)
			(fill no)
			(layer "F.Fab")
		)
		(pad "1" smd rect
			(at 0 -0.9652 180)
			(size 1.397 1.143)
			(layers "F.Cu" "F.Mask" "F.Paste")
			(net "P12V_HDD34")
		)
		(pad "2" smd rect
			(at 0 0.9652 180)
			(size 1.397 1.143)
			(layers "F.Cu" "F.Mask" "F.Paste")
			(net "GND")
		)
	)
	(footprint ""
		(layer "F.Cu")
		(at 115.062 -134.493 180)
		(property "Reference" "Q65"
			(at 0 0 180)
			(layer "F.SilkS")
			(hide yes)
			(effects
				(font
					(size 1.27 1.27)
				)
			)
		)
		(property "Value" "2N7002KDW-GP"
			(at -2.3622 -8.2042 180)
			(unlocked yes)
			(layer "F.Fab")
			(hide yes)
			(effects
				(font
					(size 1.016 1.016)
					(thickness 0.1524)
				)
			)
		)
		(property "Device Type" "SOT-363H44"
			(at -2.3622 -10.1092 180)
			(unlocked yes)
			(layer "F.Fab")
			(hide yes)
			(effects
				(font
					(size 1.016 1.016)
					(thickness 0.1524)
				)
			)
		)
		(duplicate_pad_numbers_are_jumpers no)
		(fp_line
			(start 1.4478 1.7018)
			(end 1.4478 -1.7018)
			(stroke
				(width 0.1524)
				(type default)
			)
			(layer "F.SilkS")
		)
		(fp_line
			(start 1.4478 -1.7018)
			(end -1.4478 -1.7018)
			(stroke
				(width 0.1524)
				(type default)
			)
			(layer "F.SilkS")
		)
		(fp_line
			(start -1.27 1.524)
			(end -1.27 0.6604)
			(stroke
				(width 0.4826)
				(type default)
			)
			(layer "F.SilkS")
		)
		(fp_line
			(start -1.4478 1.7018)
			(end 1.4478 1.7018)
			(stroke
				(width 0.1524)
				(type default)
			)
			(layer "F.SilkS")
		)
		(fp_line
			(start -1.4478 -1.7018)
			(end -1.4478 1.7018)
			(stroke
				(width 0.1524)
				(type default)
			)
			(layer "F.SilkS")
		)
		(fp_poly
			(pts
				(xy -1.524 -1.778) (xy 1.524 -1.778) (xy 1.524 1.778) (xy -1.524 1.778)
			)
			(stroke
				(width 0)
				(type default)
			)
			(fill no)
			(layer "F.CrtYd")
		)
		(fp_poly
			(pts
				(xy -1.524 -1.778) (xy 1.524 -1.778) (xy 1.524 1.778) (xy -1.524 1.778)
			)
			(stroke
				(width 0)
				(type default)
			)
			(fill no)
			(layer "F.Fab")
		)
		(pad "1" smd rect
			(at -0.65024 0.9398 180)
			(size 0.4064 1.016)
			(layers "F.Cu" "F.Mask" "F.Paste")
			(net "GND")
		)
		(pad "2" smd rect
			(at 0 0.9398 180)
			(size 0.4064 1.016)
			(layers "F.Cu" "F.Mask" "F.Paste")
			(net "SW_PWR_R_HDD15")
		)
		(pad "3" smd rect
			(at 0.65024 0.9398 180)
			(size 0.4064 1.016)
			(layers "F.Cu" "F.Mask" "F.Paste")
			(net "SW_HDD_P15")
		)
		(pad "4" smd rect
			(at 0.65024 -0.9398 180)
			(size 0.4064 1.016)
			(layers "F.Cu" "F.Mask" "F.Paste")
			(net "GND")
		)
		(pad "5" smd rect
			(at 0 -0.9398 180)
			(size 0.4064 1.016)
			(layers "F.Cu" "F.Mask" "F.Paste")
			(net "SW_HDD_G15")
		)
		(pad "6" smd rect
			(at -0.65024 -0.9398 180)
			(size 0.4064 1.016)
			(layers "F.Cu" "F.Mask" "F.Paste")
			(net "SW_HDD_R15")
		)
	)
	(footprint ""
		(layer "F.Cu")
		(at 145.161 -35.687 90)
		(property "Reference" "R715"
			(at 0 0 90)
			(layer "F.SilkS")
			(hide yes)
			(effects
				(font
					(size 1.27 1.27)
				)
			)
		)
		(property "Value" "2R6F-GP"
			(at -0.0508 -4.8514 90)
			(unlocked yes)
			(layer "F.Fab")
			(hide yes)
			(effects
				(font
					(size 1.016 1.016)
					(thickness 0.1524)
				)
			)
		)
		(property "Device Type" "R1206H26"
			(at 0 -6.3754 90)
			(unlocked yes)
			(layer "F.Fab")
			(hide yes)
			(effects
				(font
					(size 1.016 1.016)
					(thickness 0.1524)
				)
			)
		)
		(duplicate_pad_numbers_are_jumpers no)
		(fp_line
			(start 1.016 -2.2352)
			(end 1.016 2.2352)
			(stroke
				(width 0.1524)
				(type default)
			)
			(layer "F.SilkS")
		)
		(fp_line
			(start -1.016 -2.2352)
			(end 1.016 -2.2352)
			(stroke
				(width 0.1524)
				(type default)
			)
			(layer "F.SilkS")
		)
		(fp_line
			(start 1.016 2.2352)
			(end -1.016 2.2352)
			(stroke
				(width 0.1524)
				(type default)
			)
			(layer "F.SilkS")
		)
		(fp_line
			(start -1.016 2.2352)
			(end -1.016 -2.2352)
			(stroke
				(width 0.1524)
				(type default)
			)
			(layer "F.SilkS")
		)
		(fp_rect
			(start -1.0922 2.3114)
			(end 1.0922 -2.3114)
			(stroke
				(width 0)
				(type default)
			)
			(fill no)
			(layer "F.CrtYd")
		)
		(fp_poly
			(pts
				(xy -1.0922 -2.3114) (xy 1.0922 -2.3114) (xy 1.0922 2.3114) (xy -1.0922 2.3114)
			)
			(stroke
				(width 0)
				(type default)
			)
			(fill no)
			(layer "F.Fab")
		)
		(pad "1" smd rect
			(at 0 -1.397 90)
			(size 1.651 1.27)
			(layers "F.Cu" "F.Mask" "F.Paste")
			(net "P12V_HDD28")
		)
		(pad "2" smd rect
			(at 0 1.397 90)
			(size 1.651 1.27)
			(layers "F.Cu" "F.Mask" "F.Paste")
			(net "12V_PRE_28")
		)
	)
	(footprint ""
		(layer "F.Cu")
		(at 73.861168 -214.860378 90)
		(property "Reference" "Q245"
			(at 0 0 90)
			(layer "F.SilkS")
			(hide yes)
			(effects
				(font
					(size 1.27 1.27)
				)
			)
		)
		(property "Value" "SSM3K324R-GP"
			(at 0.127 -8.9662 90)
			(unlocked yes)
			(layer "F.Fab")
			(hide yes)
			(effects
				(font
					(size 1.016 1.016)
					(thickness 0.1524)
				)
			)
		)
		(property "Device Type" "SOT23DGS2D4H35"
			(at 0.127 -10.4902 90)
			(unlocked yes)
			(layer "F.Fab")
			(hide yes)
			(effects
				(font
					(size 1.016 1.016)
					(thickness 0.1524)
				)
			)
		)
		(duplicate_pad_numbers_are_jumpers no)
		(fp_line
			(start 1.651 -1.778)
			(end -1.651 -1.778)
			(stroke
				(width 0.1524)
				(type default)
			)
			(layer "F.SilkS")
		)
		(fp_line
			(start -1.651 -1.778)
			(end -1.651 1.778)
			(stroke
				(width 0.1524)
				(type default)
			)
			(layer "F.SilkS")
		)
		(fp_line
			(start 1.651 1.778)
			(end 1.651 -1.778)
			(stroke
				(width 0.1524)
				(type default)
			)
			(layer "F.SilkS")
		)
		(fp_line
			(start -1.651 1.778)
			(end 1.651 1.778)
			(stroke
				(width 0.1524)
				(type default)
			)
			(layer "F.SilkS")
		)
		(fp_poly
			(pts
				(xy -1.778 1.8796) (xy -1.778 -1.8796) (xy 1.778 -1.8796) (xy 1.778 1.8796)
			)
			(stroke
				(width 0)
				(type default)
			)
			(fill no)
			(layer "F.CrtYd")
		)
		(fp_poly
			(pts
				(xy -1.778 1.8796) (xy -1.778 -1.8796) (xy 1.778 -1.8796) (xy 1.778 1.8796)
			)
			(stroke
				(width 0)
				(type default)
			)
			(fill no)
			(layer "F.Fab")
		)
		(pad "D" smd custom
			(at 0 -0.9525 90)
			(size 0.1905 0.1905)
			(layers "F.Cu" "F.Mask" "F.Paste")
			(net "DRV_ACT_2_N")
			(options
				(clearance outline)
				(anchor circle)
			)
			(primitives
				(gr_poly
					(pts
						(arc
							(start -0.1778 0.5715)
							(mid -0.321484 0.511984)
							(end -0.381 0.3683)
						)
						(arc
							(start -0.381 -0.3683)
							(mid -0.321484 -0.511984)
							(end -0.1778 -0.5715)
						)
						(arc
							(start 0.1778 -0.5715)
							(mid 0.321484 -0.511984)
							(end 0.381 -0.3683)
						)
						(arc
							(start 0.381 0.3683)
							(mid 0.321484 0.511984)
							(end 0.1778 0.5715)
						)
					)
					(width 0)
					(fill yes)
				)
			)
		)
		(pad "G" smd custom
			(at -0.98425 0.9525 90)
			(size 0.1905 0.1905)
			(layers "F.Cu" "F.Mask" "F.Paste")
			(net "DRIVE_B_2_ACT")
			(options
				(clearance outline)
				(anchor circle)
			)
			(primitives
				(gr_poly
					(pts
						(arc
							(start -0.1778 0.5715)
							(mid -0.321484 0.511984)
							(end -0.381 0.3683)
						)
						(arc
							(start -0.381 -0.3683)
							(mid -0.321484 -0.511984)
							(end -0.1778 -0.5715)
						)
						(arc
							(start 0.1778 -0.5715)
							(mid 0.321484 -0.511984)
							(end 0.381 -0.3683)
						)
						(arc
							(start 0.381 0.3683)
							(mid 0.321484 0.511984)
							(end 0.1778 0.5715)
						)
					)
					(width 0)
					(fill yes)
				)
			)
		)
		(pad "S" smd custom
			(at 0.98425 0.9525 90)
			(size 0.1905 0.1905)
			(layers "F.Cu" "F.Mask" "F.Paste")
			(net "GND")
			(options
				(clearance outline)
				(anchor circle)
			)
			(primitives
				(gr_poly
					(pts
						(arc
							(start -0.1778 0.5715)
							(mid -0.321484 0.511984)
							(end -0.381 0.3683)
						)
						(arc
							(start -0.381 -0.3683)
							(mid -0.321484 -0.511984)
							(end -0.1778 -0.5715)
						)
						(arc
							(start 0.1778 -0.5715)
							(mid 0.321484 -0.511984)
							(end 0.381 -0.3683)
						)
						(arc
							(start 0.381 0.3683)
							(mid 0.321484 0.511984)
							(end 0.1778 0.5715)
						)
					)
					(width 0)
					(fill yes)
				)
			)
		)
	)
)
